#ISCELL
  mstr_misc prelim *
  *
#ISCELL
  mstr_symbols design_note *
  *
#ISCELL
  mstr_symbols intel_corp_bpage *
  *
#ISCELL
  mstr_standard offpage *
  page60_i1
#ISCELL
  mstr_standard tap *
  page60_i10
#ISCELL
  mstr_standard tap *
  page60_i100
#ISCELL
  mstr_standard tap *
  page60_i101
#ISCELL
  mstr_standard tap *
  page60_i102
#ISCELL
  mstr_standard tap *
  page60_i103
#ISCELL
  mstr_standard tap *
  page60_i104
#ISCELL
  mstr_standard tap *
  page60_i105
#ISCELL
  mstr_standard tap *
  page60_i106
#ISCELL
  mstr_standard tap *
  page60_i107
#ISCELL
  mstr_standard tap *
  page60_i108
#ISCELL
  mstr_standard tap *
  page60_i109
#ISCELL
  mstr_standard tap *
  page60_i11
#ISCELL
  mstr_standard tap *
  page60_i110
#ISCELL
  mstr_standard tap *
  page60_i111
#ISCELL
  mstr_standard tap *
  page60_i112
#ISCELL
  mstr_standard tap *
  page60_i113
#ISCELL
  mstr_standard tap *
  page60_i114
#ISCELL
  mstr_standard tap *
  page60_i115
#ISCELL
  mstr_standard tap *
  page60_i116
#ISCELL
  mstr_standard tap *
  page60_i117
#ISCELL
  mstr_standard tap *
  page60_i118
#ISCELL
  mstr_standard tap *
  page60_i119
#ISCELL
  mstr_standard tap *
  page60_i12
#ISCELL
  mstr_standard tap *
  page60_i120
#ISCELL
  mstr_standard tap *
  page60_i121
#ISCELL
  mstr_standard tap *
  page60_i122
#ISCELL
  mstr_standard tap *
  page60_i123
#ISCELL
  mstr_standard tap *
  page60_i124
#ISCELL
  mstr_standard tap *
  page60_i125
#ISCELL
  mstr_standard tap *
  page60_i126
#ISCELL
  mstr_standard tap *
  page60_i127
#ISCELL
  mstr_standard tap *
  page60_i128
#ISCELL
  mstr_standard tap *
  page60_i129
#ISCELL
  mstr_standard tap *
  page60_i13
#ISCELL
  mstr_standard tap *
  page60_i130
#ISCELL
  mstr_standard tap *
  page60_i131
#ISCELL
  mstr_standard tap *
  page60_i132
#ISCELL
  mstr_standard tap *
  page60_i133
#ISCELL
  mstr_standard tap *
  page60_i134
#ISCELL
  mstr_standard tap *
  page60_i135
#ISCELL
  mstr_standard tap *
  page60_i136
#ISCELL
  mstr_standard tap *
  page60_i137
#ISCELL
  mstr_standard tap *
  page60_i138
#ISCELL
  mstr_standard tap *
  page60_i139
#ISCELL
  mstr_standard tap *
  page60_i14
#ISCELL
  mstr_standard tap *
  page60_i140
#ISCELL
  mstr_standard tap *
  page60_i141
#ISCELL
  mstr_standard tap *
  page60_i142
#ISCELL
  mstr_standard tap *
  page60_i143
#ISCELL
  mstr_standard tap *
  page60_i144
#ISCELL
  mstr_standard tap *
  page60_i145
#ISCELL
  mstr_standard tap *
  page60_i146
#ISCELL
  mstr_standard offpage *
  page60_i147
#ISCELL
  mstr_standard offpage *
  page60_i148
#ISCELL
  mstr_standard offpage *
  page60_i149
#ISCELL
  mstr_standard tap *
  page60_i15
#ISCELL
  mstr_standard offpage *
  page60_i150
#ISCELL
  mstr_standard offpage *
  page60_i151
#ISCELL
  mstr_standard offpage *
  page60_i152
#ISCELL
  mstr_standard offpage *
  page60_i153
#ISCELL
  mstr_standard offpage *
  page60_i154
#ISCELL
  mstr_standard offpage *
  page60_i155
#ISCELL
  mstr_standard offpage *
  page60_i156
#ISCELL
  mstr_standard tap *
  page60_i157
#ISCELL
  mstr_standard tap *
  page60_i158
#ISCELL
  mstr_standard tap *
  page60_i159
#ISCELL
  mstr_standard tap *
  page60_i16
#ISCELL
  mstr_standard tap *
  page60_i160
#ISCELL
  mstr_standard tap *
  page60_i161
#ISCELL
  mstr_standard tap *
  page60_i162
#ISCELL
  mstr_standard tap *
  page60_i163
#ISCELL
  mstr_standard tap *
  page60_i164
#ISCELL
  mstr_standard tap *
  page60_i165
#ISCELL
  mstr_standard tap *
  page60_i166
#ISCELL
  mstr_standard tap *
  page60_i167
#ISCELL
  mstr_standard tap *
  page60_i168
#ISCELL
  mstr_standard tap *
  page60_i169
#ISCELL
  mstr_standard tap *
  page60_i17
#ISCELL
  mstr_standard tap *
  page60_i170
#ISCELL
  mstr_standard offpage *
  page60_i171
#CELL
  chpset_lib skx_ext_b *
  page60_i172
#ISCELL
  mstr_standard tap *
  page60_i18
#ISCELL
  mstr_standard tap *
  page60_i19
#ISCELL
  mstr_standard offpage *
  page60_i2
#ISCELL
  mstr_standard tap *
  page60_i20
#ISCELL
  mstr_standard tap *
  page60_i21
#ISCELL
  mstr_standard tap *
  page60_i22
#ISCELL
  mstr_standard tap *
  page60_i23
#ISCELL
  mstr_standard tap *
  page60_i24
#ISCELL
  mstr_standard tap *
  page60_i25
#ISCELL
  mstr_standard tap *
  page60_i26
#ISCELL
  mstr_standard tap *
  page60_i27
#ISCELL
  mstr_standard tap *
  page60_i28
#ISCELL
  mstr_standard tap *
  page60_i29
#ISCELL
  mstr_standard offpage *
  page60_i3
#ISCELL
  mstr_standard tap *
  page60_i31
#ISCELL
  mstr_standard tap *
  page60_i32
#ISCELL
  mstr_standard tap *
  page60_i33
#ISCELL
  mstr_standard tap *
  page60_i34
#ISCELL
  mstr_standard tap *
  page60_i35
#ISCELL
  mstr_standard tap *
  page60_i36
#ISCELL
  mstr_standard tap *
  page60_i37
#ISCELL
  mstr_standard tap *
  page60_i38
#ISCELL
  mstr_standard tap *
  page60_i39
#ISCELL
  mstr_standard offpage *
  page60_i4
#ISCELL
  mstr_standard tap *
  page60_i40
#ISCELL
  mstr_standard tap *
  page60_i41
#ISCELL
  mstr_standard tap *
  page60_i42
#ISCELL
  mstr_standard tap *
  page60_i43
#ISCELL
  mstr_standard tap *
  page60_i44
#ISCELL
  mstr_standard tap *
  page60_i45
#ISCELL
  mstr_standard tap *
  page60_i46
#ISCELL
  mstr_standard tap *
  page60_i47
#ISCELL
  mstr_standard tap *
  page60_i48
#ISCELL
  mstr_standard tap *
  page60_i49
#ISCELL
  mstr_standard tap *
  page60_i5
#ISCELL
  mstr_standard tap *
  page60_i50
#ISCELL
  mstr_standard tap *
  page60_i51
#ISCELL
  mstr_standard tap *
  page60_i52
#ISCELL
  mstr_standard tap *
  page60_i53
#ISCELL
  mstr_standard tap *
  page60_i54
#ISCELL
  mstr_standard tap *
  page60_i55
#ISCELL
  mstr_standard tap *
  page60_i56
#ISCELL
  mstr_standard tap *
  page60_i57
#ISCELL
  mstr_standard tap *
  page60_i58
#ISCELL
  mstr_standard tap *
  page60_i59
#ISCELL
  mstr_standard tap *
  page60_i6
#ISCELL
  mstr_standard tap *
  page60_i60
#ISCELL
  mstr_standard tap *
  page60_i61
#ISCELL
  mstr_standard tap *
  page60_i62
#ISCELL
  mstr_standard tap *
  page60_i63
#ISCELL
  mstr_standard tap *
  page60_i64
#ISCELL
  mstr_standard tap *
  page60_i65
#ISCELL
  mstr_standard tap *
  page60_i66
#ISCELL
  mstr_standard tap *
  page60_i67
#ISCELL
  mstr_standard tap *
  page60_i68
#ISCELL
  mstr_standard tap *
  page60_i69
#ISCELL
  mstr_standard tap *
  page60_i7
#ISCELL
  mstr_standard tap *
  page60_i70
#ISCELL
  mstr_standard tap *
  page60_i71
#ISCELL
  mstr_standard offpage *
  page60_i72
#ISCELL
  mstr_standard tap *
  page60_i73
#ISCELL
  mstr_standard tap *
  page60_i74
#ISCELL
  mstr_standard tap *
  page60_i75
#ISCELL
  mstr_standard tap *
  page60_i76
#ISCELL
  mstr_standard tap *
  page60_i77
#ISCELL
  mstr_standard tap *
  page60_i78
#ISCELL
  mstr_standard tap *
  page60_i79
#ISCELL
  mstr_standard tap *
  page60_i8
#ISCELL
  mstr_standard tap *
  page60_i80
#ISCELL
  mstr_standard tap *
  page60_i81
#ISCELL
  mstr_standard tap *
  page60_i82
#ISCELL
  mstr_standard tap *
  page60_i83
#ISCELL
  mstr_standard tap *
  page60_i84
#ISCELL
  mstr_standard tap *
  page60_i85
#ISCELL
  mstr_standard tap *
  page60_i86
#ISCELL
  mstr_standard tap *
  page60_i87
#ISCELL
  mstr_standard tap *
  page60_i88
#ISCELL
  mstr_standard tap *
  page60_i89
#ISCELL
  mstr_standard tap *
  page60_i9
#ISCELL
  mstr_standard tap *
  page60_i90
#ISCELL
  mstr_standard tap *
  page60_i91
#ISCELL
  mstr_standard tap *
  page60_i92
#ISCELL
  mstr_standard tap *
  page60_i93
#ISCELL
  mstr_standard tap *
  page60_i94
#ISCELL
  mstr_standard tap *
  page60_i95
#ISCELL
  mstr_standard tap *
  page60_i96
#ISCELL
  mstr_standard tap *
  page60_i97
#ISCELL
  mstr_standard tap *
  page60_i98
#ISCELL
  mstr_standard tap *
  page60_i99
